# BASEBOARD_FAB2 (Tioga Pass) — schematic netlist excerpt (pin names and nets, part order shuffled) for the footprints in the layout excerpt that follows; sources: Cadence DE-HDL packaged netlist, KiCad conversion of Wiwynn_Tioga_Pass_MB.brd

R25W61  RES  100.0K 1% CHIP  pkg 0402  page 145 : A = CLK_100M_BMC_PE_R_DP ; B = GND

(kicad_pcb
	(version 20260206)
	(generator "pcbnew")
	(generator_version "10.0")
	(general
		(thickness 1.6)
		(legacy_teardrops no)
	)
	(paper "A4")
	(title_block
		(title "Wiwynn_Tioga_Pass_MB.brd")
		(comment 1 "Tioga Pass / footprints 1356-1356 of 4770")
	)
	(layers
		(0 "F.Cu" signal "TOP")
		(4 "In1.Cu" signal "L2GND")
		(6 "In2.Cu" signal "L3")
		(8 "In3.Cu" signal "L4GND")
		(10 "In4.Cu" signal "L5")
		(12 "In5.Cu" signal "L6GND")
		(14 "In6.Cu" signal "L7VCC")
		(16 "In7.Cu" signal "L8VCC")
		(18 "In8.Cu" signal "L9GND")
		(20 "In9.Cu" signal "L10")
		(22 "In10.Cu" signal "L11GND")
		(24 "In11.Cu" signal "L12")
		(26 "In12.Cu" signal "L13GND")
		(2 "B.Cu" signal "BOTTOM")
		(9 "F.Adhes" user "F.Adhesive")
		(11 "B.Adhes" user "B.Adhesive")
		(13 "F.Paste" user "Package Geometry/Pastemask Top")
		(15 "B.Paste" user "Package Geometry/Pastemask Bottom")
		(5 "F.SilkS" user "Ref Des/Silkscreen Top")
		(7 "B.SilkS" user "Ref Des/Silkscreen Bottom")
		(1 "F.Mask" user "Board Geometry/Soldermask Top")
		(3 "B.Mask" user "Board Geometry/Soldermask Bottom")
		(17 "Dwgs.User" user "User.Drawings")
		(19 "Cmts.User" user "User.Comments")
		(21 "Eco1.User" user "User.Eco1")
		(23 "Eco2.User" user "User.Eco2")
		(25 "Edge.Cuts" user "Board Geometry/Outline")
		(27 "Margin" user)
		(31 "F.CrtYd" user "Package Geometry/Place Bound Top")
		(29 "B.CrtYd" user "Package Geometry/Place Bound Bottom")
		(35 "F.Fab" user "Ref Des/Assembly Top")
		(33 "B.Fab" user "Ref Des/Assembly Bottom")
	)
	(footprint ""
		(layer "F.Cu")
		(at 411.130242 -47.682404 180)
		(property "Reference" "R25W61"
			(at -0.8382 -0.67818 180)
			(unlocked yes)
			(layer "F.SilkS")
			(effects
				(font
					(size 0.4064 0.254)
					(thickness 0.1524)
				)
				(justify left)
			)
		)
		(property "Value" ""
			(at 0 0 180)
			(layer "F.Fab")
			(effects
				(font
					(size 1.27 1.27)
				)
			)
		)
		(duplicate_pad_numbers_are_jumpers no)
		(fp_poly
			(pts
				(xy -0.2794 -0.1016) (xy 0.2794 -0.1016) (xy 0.2794 0.9906) (xy -0.2794 0.9906)
			)
			(stroke
				(width 0)
				(type default)
			)
			(fill no)
			(layer "F.CrtYd")
		)
		(fp_line
			(start 0.2794 0.9906)
			(end 0.2794 -0.1016)
			(stroke
				(width 0.1)
				(type default)
			)
			(layer "F.Fab")
		)
		(fp_line
			(start 0.2794 -0.1016)
			(end -0.2794 -0.1016)
			(stroke
				(width 0.1)
				(type default)
			)
			(layer "F.Fab")
		)
		(fp_line
			(start -0.2794 0.9906)
			(end 0.2794 0.9906)
			(stroke
				(width 0.1)
				(type default)
			)
			(layer "F.Fab")
		)
		(fp_line
			(start -0.2794 -0.1016)
			(end -0.2794 0.9906)
			(stroke
				(width 0.1)
				(type default)
			)
			(layer "F.Fab")
		)
		(pad "1" smd rect
			(at 0 0 180)
			(size 0.508 0.508)
			(layers "F.Cu" "F.Mask" "F.Paste")
			(net "CLK_100M_BMC_PE_R_DP")
		)
		(pad "2" smd rect
			(at 0 0.889 180)
			(size 0.508 0.508)
			(layers "F.Cu" "F.Mask" "F.Paste")
			(net "GND")
		)
		(zone
			(layer "F.Cu")
			(hatch none 0.5)
			(connect_pads
				(clearance 0)
			)
			(min_thickness 0.25)
			(keepout
				(tracks not_allowed)
				(vias allowed)
				(pads allowed)
				(copperpour not_allowed)
				(footprints allowed)
			)
			(placement
				(enabled no)
				(sheetname "")
			)
			(fill
				(thermal_gap 0.5)
				(thermal_bridge_width 0.5)
				(island_removal_mode 0)
			)
			(polygon
				(pts
					(xy 411.384242 -48.317404) (xy 410.876242 -48.317404) (xy 410.876242 -47.936404) (xy 411.384242 -47.936404)
				)
			)
		)
		(zone
			(layer "F.Cu")
			(hatch none 0.5)
			(connect_pads
				(clearance 0)
			)
			(min_thickness 0.25)
			(keepout
				(tracks allowed)
				(vias not_allowed)
				(pads allowed)
				(copperpour not_allowed)
				(footprints allowed)
			)
			(placement
				(enabled no)
				(sheetname "")
			)
			(fill
				(thermal_gap 0.5)
				(thermal_bridge_width 0.5)
				(island_removal_mode 0)
			)
			(polygon
				(pts
					(xy 411.384242 -47.936404) (xy 410.876242 -47.936404) (xy 410.876242 -48.317404) (xy 411.384242 -48.317404)
				)
			)
		)
	)
)
